# SCM (Grand Teton) — schematic netlist excerpt (pin names and nets, part order shuffled) for the footprints in the layout excerpt that follows; sources: Cadence DE-HDL packaged netlist, KiCad conversion of 12092022_DA0F0TMDCD0_F0T_Management_Board_D_brd_V3_OCP.brd

H5  HOLE  EMPTY  pkg TH  page 57 : \1\ = GND
PR205  Q_RES  0 5% EMPTY  pkg 0402LF  page 56 : A = P5V_AUX ; B = PVCC2_AUX
R550  Q_RES  33.2 1% CHIP  pkg 0402LF  page 21 : A = SPI_BMC_IO0_FLASH_R ; B = SPI_BMC_BOOT_MOSI

(kicad_pcb
	(version 20260206)
	(generator "pcbnew")
	(generator_version "10.0")
	(general
		(thickness 1.6)
		(legacy_teardrops no)
	)
	(paper "A4")
	(title_block
		(title "12092022_DA0F0TMDCD0_F0T_Management_Board_D_brd_V3_OCP.brd")
		(comment 1 "Grand Teton / footprints 255-257 of 1440")
	)
	(layers
		(0 "F.Cu" signal "TOP")
		(4 "In1.Cu" signal "GND")
		(6 "In2.Cu" signal "IN1")
		(8 "In3.Cu" signal "GND1")
		(10 "In4.Cu" signal "IN2")
		(12 "In5.Cu" signal "VCC")
		(14 "In6.Cu" signal "VCC1")
		(16 "In7.Cu" signal "IN3")
		(18 "In8.Cu" signal "GND2")
		(20 "In9.Cu" signal "IN4")
		(22 "In10.Cu" signal "GND3")
		(2 "B.Cu" signal "BOTTOM")
		(9 "F.Adhes" user "F.Adhesive")
		(11 "B.Adhes" user "B.Adhesive")
		(13 "F.Paste" user "Package Geometry/Pastemask Top")
		(15 "B.Paste" user "Package Geometry/Pastemask Bottom")
		(5 "F.SilkS" user "Ref Des/Silkscreen Top")
		(7 "B.SilkS" user "Ref Des/Silkscreen Bottom")
		(1 "F.Mask" user "Board Geometry/Soldermask Top")
		(3 "B.Mask" user "Board Geometry/Soldermask Bottom")
		(17 "Dwgs.User" user "User.Drawings")
		(19 "Cmts.User" user "User.Comments")
		(21 "Eco1.User" user "User.Eco1")
		(23 "Eco2.User" user "User.Eco2")
		(25 "Edge.Cuts" user "Board Geometry/Outline")
		(27 "Margin" user)
		(31 "F.CrtYd" user "Package Geometry/Place Bound Top")
		(29 "B.CrtYd" user "Package Geometry/Place Bound Bottom")
		(35 "F.Fab" user "Ref Des/Assembly Top")
		(33 "B.Fab" user "Ref Des/Assembly Bottom")
	)
	(footprint ""
		(layer "F.Cu")
		(at 25.3238 -30.6324 90)
		(property "Reference" "PR205"
			(at 0 0 90)
			(layer "F.SilkS")
			(hide yes)
			(effects
				(font
					(size 1.27 1.27)
				)
			)
		)
		(property "Value" ""
			(at 0 0 90)
			(layer "F.Fab")
			(effects
				(font
					(size 1.27 1.27)
				)
			)
		)
		(duplicate_pad_numbers_are_jumpers no)
		(fp_line
			(start 0.7874 -0.4064)
			(end 0.7874 0.4064)
			(stroke
				(width 0.1524)
				(type default)
			)
			(layer "F.SilkS")
		)
		(fp_line
			(start -0.7874 -0.4064)
			(end 0.7874 -0.4064)
			(stroke
				(width 0.1524)
				(type default)
			)
			(layer "F.SilkS")
		)
		(fp_line
			(start 0.7874 0.4064)
			(end -0.7874 0.4064)
			(stroke
				(width 0.1524)
				(type default)
			)
			(layer "F.SilkS")
		)
		(fp_line
			(start -0.7874 0.4064)
			(end -0.7874 -0.4064)
			(stroke
				(width 0.1524)
				(type default)
			)
			(layer "F.SilkS")
		)
		(fp_line
			(start -0.12065 -0.305054)
			(end -0.12065 -0.2794)
			(stroke
				(width 0.1)
				(type default)
			)
			(layer "F.Fab")
		)
		(fp_line
			(start -0.67945 -0.305054)
			(end -0.12065 -0.305054)
			(stroke
				(width 0.1)
				(type default)
			)
			(layer "F.Fab")
		)
		(fp_line
			(start 0.67945 -0.3048)
			(end 0.67945 0.3048)
			(stroke
				(width 0.1)
				(type default)
			)
			(layer "F.Fab")
		)
		(fp_line
			(start 0.12065 -0.3048)
			(end 0.67945 -0.3048)
			(stroke
				(width 0.1)
				(type default)
			)
			(layer "F.Fab")
		)
		(fp_line
			(start 0.12065 -0.2794)
			(end 0.12065 -0.3048)
			(stroke
				(width 0.1)
				(type default)
			)
			(layer "F.Fab")
		)
		(fp_line
			(start -0.12065 -0.2794)
			(end 0.12065 -0.2794)
			(stroke
				(width 0.1)
				(type default)
			)
			(layer "F.Fab")
		)
		(fp_line
			(start 0.120396 0.2794)
			(end -0.12065 0.2794)
			(stroke
				(width 0.1)
				(type default)
			)
			(layer "F.Fab")
		)
		(fp_line
			(start -0.12065 0.2794)
			(end -0.12065 0.3048)
			(stroke
				(width 0.1)
				(type default)
			)
			(layer "F.Fab")
		)
		(fp_line
			(start 0.67945 0.3048)
			(end 0.120396 0.3048)
			(stroke
				(width 0.1)
				(type default)
			)
			(layer "F.Fab")
		)
		(fp_line
			(start 0.120396 0.3048)
			(end 0.120396 0.2794)
			(stroke
				(width 0.1)
				(type default)
			)
			(layer "F.Fab")
		)
		(fp_line
			(start -0.12065 0.3048)
			(end -0.67945 0.3048)
			(stroke
				(width 0.1)
				(type default)
			)
			(layer "F.Fab")
		)
		(fp_line
			(start -0.67945 0.3048)
			(end -0.67945 -0.305054)
			(stroke
				(width 0.1)
				(type default)
			)
			(layer "F.Fab")
		)
		(pad "1" smd circle
			(at -0.40005 0 90)
			(size 0 0)
			(layers "F.Cu" "F.Mask" "F.Paste")
			(net "P5V_AUX")
		)
		(pad "2" smd circle
			(at 0.40005 0 90)
			(size 0 0)
			(layers "F.Cu" "F.Mask" "F.Paste")
			(net "PVCC2_AUX")
		)
	)
	(footprint ""
		(layer "F.Cu")
		(at 6.100064 -22.690074)
		(property "Reference" "H5"
			(at -5.007864 -0.130556 0)
			(unlocked yes)
			(layer "F.SilkS")
			(effects
				(font
					(size 0.7874 0.5842)
					(thickness 0.1524)
				)
				(justify left)
			)
		)
		(property "Value" ""
			(at 0 0 0)
			(layer "F.Fab")
			(effects
				(font
					(size 1.27 1.27)
				)
			)
		)
		(duplicate_pad_numbers_are_jumpers no)
		(pad "1" thru_hole circle
			(at 0 0)
			(size 6.0452 6.0452)
			(drill 3.1496)
			(layers "*.Cu" "*.Mask")
			(remove_unused_layers no)
			(net "GND")
			(clearance -1.1938)
		)
	)
	(footprint ""
		(layer "F.Cu")
		(at 39.8272 -76.454)
		(property "Reference" "R550"
			(at 0 0 0)
			(layer "F.SilkS")
			(hide yes)
			(effects
				(font
					(size 1.27 1.27)
				)
			)
		)
		(property "Value" ""
			(at 0 0 0)
			(layer "F.Fab")
			(effects
				(font
					(size 1.27 1.27)
				)
			)
		)
		(duplicate_pad_numbers_are_jumpers no)
		(fp_line
			(start -0.7874 -0.4064)
			(end 0.7874 -0.4064)
			(stroke
				(width 0.1524)
				(type default)
			)
			(layer "F.SilkS")
		)
		(fp_line
			(start -0.7874 0.4064)
			(end -0.7874 -0.4064)
			(stroke
				(width 0.1524)
				(type default)
			)
			(layer "F.SilkS")
		)
		(fp_line
			(start 0.7874 -0.4064)
			(end 0.7874 0.4064)
			(stroke
				(width 0.1524)
				(type default)
			)
			(layer "F.SilkS")
		)
		(fp_line
			(start 0.7874 0.4064)
			(end -0.7874 0.4064)
			(stroke
				(width 0.1524)
				(type default)
			)
			(layer "F.SilkS")
		)
		(fp_line
			(start -0.67945 -0.305054)
			(end -0.12065 -0.305054)
			(stroke
				(width 0.1)
				(type default)
			)
			(layer "F.Fab")
		)
		(fp_line
			(start -0.67945 0.3048)
			(end -0.67945 -0.305054)
			(stroke
				(width 0.1)
				(type default)
			)
			(layer "F.Fab")
		)
		(fp_line
			(start -0.12065 -0.305054)
			(end -0.12065 -0.2794)
			(stroke
				(width 0.1)
				(type default)
			)
			(layer "F.Fab")
		)
		(fp_line
			(start -0.12065 -0.2794)
			(end 0.12065 -0.2794)
			(stroke
				(width 0.1)
				(type default)
			)
			(layer "F.Fab")
		)
		(fp_line
			(start -0.12065 0.2794)
			(end -0.12065 0.3048)
			(stroke
				(width 0.1)
				(type default)
			)
			(layer "F.Fab")
		)
		(fp_line
			(start -0.12065 0.3048)
			(end -0.67945 0.3048)
			(stroke
				(width 0.1)
				(type default)
			)
			(layer "F.Fab")
		)
		(fp_line
			(start 0.120396 0.2794)
			(end -0.12065 0.2794)
			(stroke
				(width 0.1)
				(type default)
			)
			(layer "F.Fab")
		)
		(fp_line
			(start 0.120396 0.3048)
			(end 0.120396 0.2794)
			(stroke
				(width 0.1)
				(type default)
			)
			(layer "F.Fab")
		)
		(fp_line
			(start 0.12065 -0.3048)
			(end 0.67945 -0.3048)
			(stroke
				(width 0.1)
				(type default)
			)
			(layer "F.Fab")
		)
		(fp_line
			(start 0.12065 -0.2794)
			(end 0.12065 -0.3048)
			(stroke
				(width 0.1)
				(type default)
			)
			(layer "F.Fab")
		)
		(fp_line
			(start 0.67945 -0.3048)
			(end 0.67945 0.3048)
			(stroke
				(width 0.1)
				(type default)
			)
			(layer "F.Fab")
		)
		(fp_line
			(start 0.67945 0.3048)
			(end 0.120396 0.3048)
			(stroke
				(width 0.1)
				(type default)
			)
			(layer "F.Fab")
		)
		(pad "1" smd circle
			(at -0.40005 0)
			(size 0 0)
			(layers "F.Cu" "F.Mask" "F.Paste")
			(net "SPI_BMC_IO0_FLASH_R")
		)
		(pad "2" smd circle
			(at 0.40005 0)
			(size 0 0)
			(layers "F.Cu" "F.Mask" "F.Paste")
			(net "SPI_BMC_BOOT_MOSI")
		)
	)
)
